(kicad_pcb
	(version 20260206)
	(generator "pcbnew")
	(generator_version "10.0")
	(general
		(thickness 1.6)
		(legacy_teardrops no)
	)
	(paper "A4")
	(title_block
		(title "fcb — 12433-1M.1206WZS1330.brd")
		(comment 1 "Open Vault / Knox (Wiwynn) / footprints 314-320 of 495")
	)
	(layers
		(0 "F.Cu" signal "TOP")
		(4 "In1.Cu" signal "L2GND")
		(6 "In2.Cu" signal "L3VCC")
		(2 "B.Cu" signal "BOTTOM")
		(9 "F.Adhes" user "F.Adhesive")
		(11 "B.Adhes" user "B.Adhesive")
		(13 "F.Paste" user "Package Geometry/Pastemask Top")
		(15 "B.Paste" user "Package Geometry/Pastemask Bottom")
		(5 "F.SilkS" user "Ref Des/Silkscreen Top")
		(7 "B.SilkS" user "Ref Des/Silkscreen Bottom")
		(1 "F.Mask" user "Board Geometry/Soldermask Top")
		(3 "B.Mask" user "Board Geometry/Soldermask Bottom")
		(17 "Dwgs.User" user "User.Drawings")
		(19 "Cmts.User" user "User.Comments")
		(21 "Eco1.User" user "User.Eco1")
		(23 "Eco2.User" user "User.Eco2")
		(25 "Edge.Cuts" user "Board Geometry/Outline")
		(27 "Margin" user)
		(31 "F.CrtYd" user "Package Geometry/Place Bound Top")
		(29 "B.CrtYd" user "Package Geometry/Place Bound Bottom")
		(35 "F.Fab" user "Ref Des/Assembly Top")
		(33 "B.Fab" user "Ref Des/Assembly Bottom")
	)
	(footprint ""
		(layer "F.Cu")
		(at 36.1188 -372.4656 -90)
		(property "Reference" "PR7"
			(at 0 0 270)
			(layer "F.SilkS")
			(hide yes)
			(effects
				(font
					(size 1.27 1.27)
				)
			)
		)
		(property "Value" "1KR2F-3-GP"
			(at 0.064008 -3.993896 270)
			(unlocked yes)
			(layer "F.Fab")
			(hide yes)
			(effects
				(font
					(size 1.016 1.016)
					(thickness 0.1524)
				)
			)
		)
		(property "Device Type" "R402H16"
			(at 0.064008 -5.517896 270)
			(unlocked yes)
			(layer "F.Fab")
			(hide yes)
			(effects
				(font
					(size 1.016 1.016)
					(thickness 0.1524)
				)
			)
		)
		(duplicate_pad_numbers_are_jumpers no)
		(fp_line
			(start -0.508 -0.9398)
			(end -0.508 0.9398)
			(stroke
				(width 0.1524)
				(type default)
			)
			(layer "F.SilkS")
		)
		(fp_line
			(start 0.508 -0.9398)
			(end -0.508 -0.9398)
			(stroke
				(width 0.1524)
				(type default)
			)
			(layer "F.SilkS")
		)
		(fp_rect
			(start -0.508 0.9398)
			(end 0.508 -0.9398)
			(stroke
				(width 0)
				(type default)
			)
			(fill no)
			(layer "F.CrtYd")
		)
		(fp_rect
			(start -0.508 0.9398)
			(end 0.508 -0.9398)
			(stroke
				(width 0)
				(type default)
			)
			(fill no)
			(layer "F.Fab")
		)
		(pad "1" smd custom
			(at 0 -0.4445 270)
			(size 0.1397 0.1397)
			(layers "F.Cu" "F.Mask" "F.Paste")
			(net "P12V")
			(options
				(clearance outline)
				(anchor circle)
			)
			(primitives
				(gr_poly
					(pts
						(arc
							(start -0.1778 -0.2794)
							(mid -0.249642 -0.249642)
							(end -0.2794 -0.1778)
						)
						(arc
							(start -0.2794 0.1778)
							(mid -0.249642 0.249642)
							(end -0.1778 0.2794)
						)
						(arc
							(start 0.1778 0.2794)
							(mid 0.249642 0.249642)
							(end 0.2794 0.1778)
						)
						(arc
							(start 0.2794 -0.1778)
							(mid 0.249642 -0.249642)
							(end 0.1778 -0.2794)
						)
					)
					(width 0)
					(fill yes)
				)
			)
		)
		(pad "2" smd custom
			(at 0 0.4445 270)
			(size 0.1397 0.1397)
			(layers "F.Cu" "F.Mask" "F.Paste")
			(net "ADM1276_VOUT")
			(options
				(clearance outline)
				(anchor circle)
			)
			(primitives
				(gr_poly
					(pts
						(arc
							(start -0.1778 -0.2794)
							(mid -0.249642 -0.249642)
							(end -0.2794 -0.1778)
						)
						(arc
							(start -0.2794 0.1778)
							(mid -0.249642 0.249642)
							(end -0.1778 0.2794)
						)
						(arc
							(start 0.1778 0.2794)
							(mid 0.249642 0.249642)
							(end 0.2794 0.1778)
						)
						(arc
							(start 0.2794 -0.1778)
							(mid 0.249642 -0.249642)
							(end 0.1778 -0.2794)
						)
					)
					(width 0)
					(fill yes)
				)
			)
		)
	)
	(footprint ""
		(layer "F.Cu")
		(at 4.040124 -127.340106 -90)
		(property "Reference" "CN5"
			(at 0 0 270)
			(layer "F.SilkS")
			(hide yes)
			(effects
				(font
					(size 1.27 1.27)
				)
			)
		)
		(property "Value" "JWT-CON5-42-GP"
			(at -7.8105 2.9591 270)
			(unlocked yes)
			(layer "F.Fab")
			(hide yes)
			(effects
				(font
					(size 1.016 1.016)
					(thickness 0.1524)
				)
			)
		)
		(property "Device Type" "A2541WR0-1TX5PA-6T-0E"
			(at -7.8105 1.4351 270)
			(unlocked yes)
			(layer "F.Fab")
			(hide yes)
			(effects
				(font
					(size 1.016 1.016)
					(thickness 0.1524)
				)
			)
		)
		(duplicate_pad_numbers_are_jumpers no)
		(fp_line
			(start -6.604 10.287)
			(end 6.604 10.287)
			(stroke
				(width 0.1524)
				(type default)
			)
			(layer "F.SilkS")
		)
		(fp_line
			(start 6.604 10.287)
			(end 6.604 -0.9652)
			(stroke
				(width 0.1524)
				(type default)
			)
			(layer "F.SilkS")
		)
		(fp_line
			(start -6.604 -0.9652)
			(end -6.604 10.287)
			(stroke
				(width 0.1524)
				(type default)
			)
			(layer "F.SilkS")
		)
		(fp_line
			(start 6.604 -0.9652)
			(end -6.604 -0.9652)
			(stroke
				(width 0.1524)
				(type default)
			)
			(layer "F.SilkS")
		)
		(fp_line
			(start -6.731 -1.0922)
			(end -6.731 0.1778)
			(stroke
				(width 0.4064)
				(type default)
			)
			(layer "F.SilkS")
		)
		(fp_line
			(start -5.461 -1.0922)
			(end -6.731 -1.0922)
			(stroke
				(width 0.4064)
				(type default)
			)
			(layer "F.SilkS")
		)
		(fp_circle
			(center -5.08 0)
			(end -5.08 -1.0668)
			(stroke
				(width 0.3048)
				(type default)
			)
			(fill no)
			(layer "F.SilkS")
		)
		(fp_circle
			(center -2.54 0)
			(end -2.54 -1.0668)
			(stroke
				(width 0.3048)
				(type default)
			)
			(fill no)
			(layer "F.SilkS")
		)
		(fp_circle
			(center 0 0)
			(end 0 -1.0668)
			(stroke
				(width 0.3048)
				(type default)
			)
			(fill no)
			(layer "F.SilkS")
		)
		(fp_circle
			(center 2.54 0)
			(end 2.54 -1.0668)
			(stroke
				(width 0.3048)
				(type default)
			)
			(fill no)
			(layer "F.SilkS")
		)
		(fp_circle
			(center 5.08 0)
			(end 5.08 -1.0668)
			(stroke
				(width 0.3048)
				(type default)
			)
			(fill no)
			(layer "F.SilkS")
		)
		(fp_rect
			(start -6.35 10.033)
			(end 6.35 -0.3302)
			(stroke
				(width 0)
				(type default)
			)
			(fill no)
			(layer "F.CrtYd")
		)
		(fp_poly
			(pts
				(xy -6.35 -0.3302) (xy 6.858 -0.3302) (xy 6.858 -1.2192) (xy -6.858 -1.2192) (xy -6.858 10.541)
				(xy 6.858 10.541) (xy 6.858 -0.3175) (xy 6.35 -0.3175) (xy 6.35 10.033) (xy -6.35 10.033)
			)
			(stroke
				(width 0)
				(type default)
			)
			(fill no)
			(layer "F.CrtYd")
		)
		(fp_rect
			(start -6.858 10.541)
			(end 6.858 -1.2192)
			(stroke
				(width 0)
				(type default)
			)
			(fill no)
			(layer "F.Fab")
		)
		(pad "1" thru_hole circle
			(at -5.08 0 270)
			(size 1.4224 1.4224)
			(drill 1.016)
			(layers "*.Cu" "*.Mask")
			(remove_unused_layers no)
			(net "GND")
			(clearance 0.1524)
			(thermal_gap 0.1524)
		)
		(pad "2" thru_hole circle
			(at -2.54 0 270)
			(size 1.4224 1.4224)
			(drill 1.016)
			(layers "*.Cu" "*.Mask")
			(remove_unused_layers no)
			(net "P12V_FAN5")
			(clearance 0.1524)
			(thermal_gap 0.1524)
		)
		(pad "3" thru_hole circle
			(at 0 0 270)
			(size 1.4224 1.4224)
			(drill 1.016)
			(layers "*.Cu" "*.Mask")
			(remove_unused_layers no)
			(net "FAN_TACH10")
			(clearance 0.1524)
			(thermal_gap 0.1524)
		)
		(pad "4" thru_hole circle
			(at 2.54 0 270)
			(size 1.4224 1.4224)
			(drill 1.016)
			(layers "*.Cu" "*.Mask")
			(remove_unused_layers no)
			(net "PWM_OUT_FAN5_NET")
			(clearance 0.1524)
			(thermal_gap 0.1524)
		)
		(pad "5" thru_hole circle
			(at 5.08 0 270)
			(size 1.4224 1.4224)
			(drill 1.016)
			(layers "*.Cu" "*.Mask")
			(remove_unused_layers no)
			(net "FAN_TACH9")
			(clearance 0.1524)
			(thermal_gap 0.1524)
		)
	)
	(footprint ""
		(layer "F.Cu")
		(at 14.8844 -50.6222 90)
		(property "Reference" "R175"
			(at 0 0 90)
			(layer "F.SilkS")
			(hide yes)
			(effects
				(font
					(size 1.27 1.27)
				)
			)
		)
		(property "Value" "0R2J-2-GP"
			(at 0.064008 -3.993896 90)
			(unlocked yes)
			(layer "F.Fab")
			(hide yes)
			(effects
				(font
					(size 1.016 1.016)
					(thickness 0.1524)
				)
			)
		)
		(property "Device Type" "R402H16"
			(at 0.064008 -5.517896 90)
			(unlocked yes)
			(layer "F.Fab")
			(hide yes)
			(effects
				(font
					(size 1.016 1.016)
					(thickness 0.1524)
				)
			)
		)
		(duplicate_pad_numbers_are_jumpers no)
		(fp_line
			(start 0.508 -0.9398)
			(end -0.508 -0.9398)
			(stroke
				(width 0.1524)
				(type default)
			)
			(layer "F.SilkS")
		)
		(fp_line
			(start -0.508 -0.9398)
			(end -0.508 0.9398)
			(stroke
				(width 0.1524)
				(type default)
			)
			(layer "F.SilkS")
		)
		(fp_rect
			(start -0.508 0.9398)
			(end 0.508 -0.9398)
			(stroke
				(width 0)
				(type default)
			)
			(fill no)
			(layer "F.CrtYd")
		)
		(fp_rect
			(start -0.508 0.9398)
			(end 0.508 -0.9398)
			(stroke
				(width 0)
				(type default)
			)
			(fill no)
			(layer "F.Fab")
		)
		(pad "1" smd custom
			(at 0 -0.4445 90)
			(size 0.1397 0.1397)
			(layers "F.Cu" "F.Mask" "F.Paste")
			(net "SD_LATCH_RELEASE_U")
			(options
				(clearance outline)
				(anchor circle)
			)
			(primitives
				(gr_poly
					(pts
						(arc
							(start -0.1778 -0.2794)
							(mid -0.249642 -0.249642)
							(end -0.2794 -0.1778)
						)
						(arc
							(start -0.2794 0.1778)
							(mid -0.249642 0.249642)
							(end -0.1778 0.2794)
						)
						(arc
							(start 0.1778 0.2794)
							(mid 0.249642 0.249642)
							(end 0.2794 0.1778)
						)
						(arc
							(start 0.2794 -0.1778)
							(mid 0.249642 -0.249642)
							(end 0.1778 -0.2794)
						)
					)
					(width 0)
					(fill yes)
				)
			)
		)
		(pad "2" smd custom
			(at 0 0.4445 90)
			(size 0.1397 0.1397)
			(layers "F.Cu" "F.Mask" "F.Paste")
			(net "TEMP_ALM#_REVERSE_R")
			(options
				(clearance outline)
				(anchor circle)
			)
			(primitives
				(gr_poly
					(pts
						(arc
							(start -0.1778 -0.2794)
							(mid -0.249642 -0.249642)
							(end -0.2794 -0.1778)
						)
						(arc
							(start -0.2794 0.1778)
							(mid -0.249642 0.249642)
							(end -0.1778 0.2794)
						)
						(arc
							(start 0.1778 0.2794)
							(mid 0.249642 0.249642)
							(end 0.2794 0.1778)
						)
						(arc
							(start 0.2794 -0.1778)
							(mid 0.249642 -0.249642)
							(end 0.1778 -0.2794)
						)
					)
					(width 0)
					(fill yes)
				)
			)
		)
	)
	(footprint ""
		(layer "F.Cu")
		(at 37.5666 -254.3556)
		(property "Reference" "R59"
			(at 0 0 0)
			(layer "F.SilkS")
			(hide yes)
			(effects
				(font
					(size 1.27 1.27)
				)
			)
		)
		(property "Value" "330R2J-3-GP"
			(at 0.064008 -3.993896 0)
			(unlocked yes)
			(layer "F.Fab")
			(hide yes)
			(effects
				(font
					(size 1.016 1.016)
					(thickness 0.1524)
				)
			)
		)
		(property "Device Type" "R402H16"
			(at 0.064008 -5.517896 0)
			(unlocked yes)
			(layer "F.Fab")
			(hide yes)
			(effects
				(font
					(size 1.016 1.016)
					(thickness 0.1524)
				)
			)
		)
		(duplicate_pad_numbers_are_jumpers no)
		(fp_line
			(start -0.508 -0.9398)
			(end -0.508 0.9398)
			(stroke
				(width 0.1524)
				(type default)
			)
			(layer "F.SilkS")
		)
		(fp_line
			(start 0.508 -0.9398)
			(end -0.508 -0.9398)
			(stroke
				(width 0.1524)
				(type default)
			)
			(layer "F.SilkS")
		)
		(fp_rect
			(start -0.508 0.9398)
			(end 0.508 -0.9398)
			(stroke
				(width 0)
				(type default)
			)
			(fill no)
			(layer "F.CrtYd")
		)
		(fp_rect
			(start -0.508 0.9398)
			(end 0.508 -0.9398)
			(stroke
				(width 0)
				(type default)
			)
			(fill no)
			(layer "F.Fab")
		)
		(pad "1" smd custom
			(at 0 -0.4445)
			(size 0.1397 0.1397)
			(layers "F.Cu" "F.Mask" "F.Paste")
			(net "P3V3")
			(options
				(clearance outline)
				(anchor circle)
			)
			(primitives
				(gr_poly
					(pts
						(arc
							(start -0.1778 -0.2794)
							(mid -0.249642 -0.249642)
							(end -0.2794 -0.1778)
						)
						(arc
							(start -0.2794 0.1778)
							(mid -0.249642 0.249642)
							(end -0.1778 0.2794)
						)
						(arc
							(start 0.1778 0.2794)
							(mid 0.249642 0.249642)
							(end 0.2794 0.1778)
						)
						(arc
							(start 0.2794 -0.1778)
							(mid 0.249642 -0.249642)
							(end 0.1778 -0.2794)
						)
					)
					(width 0)
					(fill yes)
				)
			)
		)
		(pad "2" smd custom
			(at 0 0.4445)
			(size 0.1397 0.1397)
			(layers "F.Cu" "F.Mask" "F.Paste")
			(net "LED_DR_LED7_RESERVE")
			(options
				(clearance outline)
				(anchor circle)
			)
			(primitives
				(gr_poly
					(pts
						(arc
							(start -0.1778 -0.2794)
							(mid -0.249642 -0.249642)
							(end -0.2794 -0.1778)
						)
						(arc
							(start -0.2794 0.1778)
							(mid -0.249642 0.249642)
							(end -0.1778 0.2794)
						)
						(arc
							(start 0.1778 0.2794)
							(mid 0.249642 0.249642)
							(end 0.2794 0.1778)
						)
						(arc
							(start 0.2794 -0.1778)
							(mid 0.249642 -0.249642)
							(end 0.1778 -0.2794)
						)
					)
					(width 0)
					(fill yes)
				)
			)
		)
	)
	(footprint ""
		(layer "F.Cu")
		(at 5.4102 -431.5968 90)
		(property "Reference" "R127"
			(at 0 0 90)
			(layer "F.SilkS")
			(hide yes)
			(effects
				(font
					(size 1.27 1.27)
				)
			)
		)
		(property "Value" "1K8R6J-GP"
			(at -0.0508 -4.8514 90)
			(unlocked yes)
			(layer "F.Fab")
			(hide yes)
			(effects
				(font
					(size 1.016 1.016)
					(thickness 0.1524)
				)
			)
		)
		(property "Device Type" "R1206H28"
			(at 0 -6.3754 90)
			(unlocked yes)
			(layer "F.Fab")
			(hide yes)
			(effects
				(font
					(size 1.016 1.016)
					(thickness 0.1524)
				)
			)
		)
		(duplicate_pad_numbers_are_jumpers no)
		(fp_line
			(start 1.016 -2.2352)
			(end 1.016 2.2352)
			(stroke
				(width 0.1524)
				(type default)
			)
			(layer "F.SilkS")
		)
		(fp_line
			(start -1.016 -2.2352)
			(end 1.016 -2.2352)
			(stroke
				(width 0.1524)
				(type default)
			)
			(layer "F.SilkS")
		)
		(fp_line
			(start 1.016 2.2352)
			(end -1.016 2.2352)
			(stroke
				(width 0.1524)
				(type default)
			)
			(layer "F.SilkS")
		)
		(fp_line
			(start -1.016 2.2352)
			(end -1.016 -2.2352)
			(stroke
				(width 0.1524)
				(type default)
			)
			(layer "F.SilkS")
		)
		(fp_rect
			(start -1.0922 2.3114)
			(end 1.0922 -2.3114)
			(stroke
				(width 0)
				(type default)
			)
			(fill no)
			(layer "F.CrtYd")
		)
		(fp_poly
			(pts
				(xy -1.0922 -2.3114) (xy 1.0922 -2.3114) (xy 1.0922 2.3114) (xy -1.0922 2.3114)
			)
			(stroke
				(width 0)
				(type default)
			)
			(fill no)
			(layer "F.Fab")
		)
		(pad "1" smd rect
			(at 0 -1.397 90)
			(size 1.651 1.27)
			(layers "F.Cu" "F.Mask" "F.Paste")
			(net "P12V")
		)
		(pad "2" smd rect
			(at 0 1.397 90)
			(size 1.651 1.27)
			(layers "F.Cu" "F.Mask" "F.Paste")
			(net "LED_DR_LED0_BLUE")
		)
	)
	(footprint ""
		(layer "F.Cu")
		(at 26.416 -374.523 -90)
		(property "Reference" "PC1"
			(at 0 0 270)
			(layer "F.SilkS")
			(hide yes)
			(effects
				(font
					(size 1.27 1.27)
				)
			)
		)
		(property "Value" "SC1U25V3KX-1-GP"
			(at 0 -2.8194 270)
			(unlocked yes)
			(layer "F.Fab")
			(hide yes)
			(effects
				(font
					(size 1.016 1.016)
					(thickness 0.1524)
				)
			)
		)
		(property "Device Type" "C603H36"
			(at 0 -4.3434 270)
			(unlocked yes)
			(layer "F.Fab")
			(hide yes)
			(effects
				(font
					(size 1.016 1.016)
					(thickness 0.1524)
				)
			)
		)
		(duplicate_pad_numbers_are_jumpers no)
		(fp_line
			(start 0.508 0)
			(end -0.508 0)
			(stroke
				(width 0.2032)
				(type default)
			)
			(layer "F.SilkS")
		)
		(fp_rect
			(start -0.5842 1.3335)
			(end 0.5842 -1.3335)
			(stroke
				(width 0)
				(type default)
			)
			(fill no)
			(layer "F.CrtYd")
		)
		(fp_rect
			(start -0.5842 1.3335)
			(end 0.5842 -1.3335)
			(stroke
				(width 0)
				(type default)
			)
			(fill no)
			(layer "F.Fab")
		)
		(pad "1" smd custom
			(at 0 -0.762 270)
			(size 0.2159 0.2159)
			(layers "F.Cu" "F.Mask" "F.Paste")
			(net "ADM1276_VCC")
			(options
				(clearance outline)
				(anchor circle)
			)
			(primitives
				(gr_poly
					(pts
						(arc
							(start -0.3302 -0.4318)
							(mid -0.402042 -0.402042)
							(end -0.4318 -0.3302)
						)
						(arc
							(start -0.4318 0.3302)
							(mid -0.402042 0.402042)
							(end -0.3302 0.4318)
						)
						(arc
							(start 0.3302 0.4318)
							(mid 0.402042 0.402042)
							(end 0.4318 0.3302)
						)
						(arc
							(start 0.4318 -0.3302)
							(mid 0.402042 -0.402042)
							(end 0.3302 -0.4318)
						)
					)
					(width 0)
					(fill yes)
				)
			)
		)
		(pad "2" smd custom
			(at 0 0.762 270)
			(size 0.2159 0.2159)
			(layers "F.Cu" "F.Mask" "F.Paste")
			(net "GND")
			(options
				(clearance outline)
				(anchor circle)
			)
			(primitives
				(gr_poly
					(pts
						(arc
							(start -0.3302 -0.4318)
							(mid -0.402042 -0.402042)
							(end -0.4318 -0.3302)
						)
						(arc
							(start -0.4318 0.3302)
							(mid -0.402042 0.402042)
							(end -0.3302 0.4318)
						)
						(arc
							(start 0.3302 0.4318)
							(mid 0.402042 0.402042)
							(end 0.4318 0.3302)
						)
						(arc
							(start 0.4318 -0.3302)
							(mid 0.402042 -0.402042)
							(end 0.3302 -0.4318)
						)
					)
					(width 0)
					(fill yes)
				)
			)
		)
	)
	(footprint ""
		(layer "F.Cu")
		(at 12.9794 -449.5292 90)
		(property "Reference" "R105"
			(at 0 0 90)
			(layer "F.SilkS")
			(hide yes)
			(effects
				(font
					(size 1.27 1.27)
				)
			)
		)
		(property "Value" "10KR2F-2-GP"
			(at 0.064008 -3.993896 90)
			(unlocked yes)
			(layer "F.Fab")
			(hide yes)
			(effects
				(font
					(size 1.016 1.016)
					(thickness 0.1524)
				)
			)
		)
		(property "Device Type" "R402H16"
			(at 0.064008 -5.517896 90)
			(unlocked yes)
			(layer "F.Fab")
			(hide yes)
			(effects
				(font
					(size 1.016 1.016)
					(thickness 0.1524)
				)
			)
		)
		(duplicate_pad_numbers_are_jumpers no)
		(fp_line
			(start 0.508 -0.9398)
			(end -0.508 -0.9398)
			(stroke
				(width 0.1524)
				(type default)
			)
			(layer "F.SilkS")
		)
		(fp_line
			(start -0.508 -0.9398)
			(end -0.508 0.9398)
			(stroke
				(width 0.1524)
				(type default)
			)
			(layer "F.SilkS")
		)
		(fp_rect
			(start -0.508 0.9398)
			(end 0.508 -0.9398)
			(stroke
				(width 0)
				(type default)
			)
			(fill no)
			(layer "F.CrtYd")
		)
		(fp_rect
			(start -0.508 0.9398)
			(end 0.508 -0.9398)
			(stroke
				(width 0)
				(type default)
			)
			(fill no)
			(layer "F.Fab")
		)
		(pad "1" smd custom
			(at 0 -0.4445 90)
			(size 0.1397 0.1397)
			(layers "F.Cu" "F.Mask" "F.Paste")
			(net "FANIN_2")
			(options
				(clearance outline)
				(anchor circle)
			)
			(primitives
				(gr_poly
					(pts
						(arc
							(start -0.1778 -0.2794)
							(mid -0.249642 -0.249642)
							(end -0.2794 -0.1778)
						)
						(arc
							(start -0.2794 0.1778)
							(mid -0.249642 0.249642)
							(end -0.1778 0.2794)
						)
						(arc
							(start 0.1778 0.2794)
							(mid 0.249642 0.249642)
							(end 0.2794 0.1778)
						)
						(arc
							(start 0.2794 -0.1778)
							(mid 0.249642 -0.249642)
							(end 0.1778 -0.2794)
						)
					)
					(width 0)
					(fill yes)
				)
			)
		)
		(pad "2" smd custom
			(at 0 0.4445 90)
			(size 0.1397 0.1397)
			(layers "F.Cu" "F.Mask" "F.Paste")
			(net "GND")
			(options
				(clearance outline)
				(anchor circle)
			)
			(primitives
				(gr_poly
					(pts
						(arc
							(start -0.1778 -0.2794)
							(mid -0.249642 -0.249642)
							(end -0.2794 -0.1778)
						)
						(arc
							(start -0.2794 0.1778)
							(mid -0.249642 0.249642)
							(end -0.1778 0.2794)
						)
						(arc
							(start 0.1778 0.2794)
							(mid 0.249642 0.249642)
							(end 0.2794 0.1778)
						)
						(arc
							(start 0.2794 -0.1778)
							(mid 0.249642 -0.249642)
							(end 0.1778 -0.2794)
						)
					)
					(width 0)
					(fill yes)
				)
			)
		)
	)
)
